# BASEBOARD_FAB2 (Tioga Pass) — schematic netlist excerpt (pin names and nets, part order shuffled) for the footprints in the layout excerpt that follows; sources: Cadence DE-HDL packaged netlist, KiCad conversion of Wiwynn_Tioga_Pass_MB.brd

Q2P1  FET_N  2N7002 FET  pkg SOT23LF  page 170
  GATE  = FM_PMBUS_ALERT_BUF_EN_N
  SRC  = GND
  DRN  = FM_PMBUS_ALERT_BUF_EN

T1D24  TEST-PAD-12P-1-GP-U  pkg DISCRET-GB1  page 258
  DP  = L14_85OHM_10INCH_DN
  DN  = L14_85OHM_10INCH_DP
  GND(0)  = GND
  GND(1)  = GND
  GND(2)  = GND
  GND(3)  = GND
  GND(4)  = GND
  GND(5)  = GND
  GND(6)  = GND
  GND(7)  = GND
  GND(8)  = GND
  GND(9)  = GND

(kicad_pcb
	(version 20260206)
	(generator "pcbnew")
	(generator_version "10.0")
	(general
		(thickness 1.6)
		(legacy_teardrops no)
	)
	(paper "A4")
	(title_block
		(title "Wiwynn_Tioga_Pass_MB.brd")
		(comment 1 "Tioga Pass / footprints 3189-3190 of 4770")
	)
	(layers
		(0 "F.Cu" signal "TOP")
		(4 "In1.Cu" signal "L2GND")
		(6 "In2.Cu" signal "L3")
		(8 "In3.Cu" signal "L4GND")
		(10 "In4.Cu" signal "L5")
		(12 "In5.Cu" signal "L6GND")
		(14 "In6.Cu" signal "L7VCC")
		(16 "In7.Cu" signal "L8VCC")
		(18 "In8.Cu" signal "L9GND")
		(20 "In9.Cu" signal "L10")
		(22 "In10.Cu" signal "L11GND")
		(24 "In11.Cu" signal "L12")
		(26 "In12.Cu" signal "L13GND")
		(2 "B.Cu" signal "BOTTOM")
		(9 "F.Adhes" user "F.Adhesive")
		(11 "B.Adhes" user "B.Adhesive")
		(13 "F.Paste" user "Package Geometry/Pastemask Top")
		(15 "B.Paste" user "Package Geometry/Pastemask Bottom")
		(5 "F.SilkS" user "Ref Des/Silkscreen Top")
		(7 "B.SilkS" user "Ref Des/Silkscreen Bottom")
		(1 "F.Mask" user "Board Geometry/Soldermask Top")
		(3 "B.Mask" user "Board Geometry/Soldermask Bottom")
		(17 "Dwgs.User" user "User.Drawings")
		(19 "Cmts.User" user "User.Comments")
		(21 "Eco1.User" user "User.Eco1")
		(23 "Eco2.User" user "User.Eco2")
		(25 "Edge.Cuts" user "Board Geometry/Outline")
		(27 "Margin" user)
		(31 "F.CrtYd" user "Package Geometry/Place Bound Top")
		(29 "B.CrtYd" user "Package Geometry/Place Bound Bottom")
		(35 "F.Fab" user "Ref Des/Assembly Top")
		(33 "B.Fab" user "Ref Des/Assembly Bottom")
	)
	(footprint ""
		(layer "B.Cu")
		(at 420.3065 -79.9465)
		(property "Reference" "Q2P1"
			(at -1.27508 3.76555 180)
			(unlocked yes)
			(layer "B.SilkS")
			(effects
				(font
					(size 0.7874 0.5842)
					(thickness 0.1524)
				)
				(justify left mirror)
			)
		)
		(property "Value" ""
			(at 0 0 0)
			(layer "B.Fab")
			(effects
				(font
					(size 1.27 1.27)
				)
				(justify mirror)
			)
		)
		(duplicate_pad_numbers_are_jumpers no)
		(fp_line
			(start -1.778 -0.5715)
			(end -1.778 0.3175)
			(stroke
				(width 0.1524)
				(type default)
			)
			(layer "B.SilkS")
		)
		(fp_line
			(start -1.778 2.4765)
			(end -1.778 1.5875)
			(stroke
				(width 0.1524)
				(type default)
			)
			(layer "B.SilkS")
		)
		(fp_line
			(start -0.9525 -0.5715)
			(end -1.778 -0.5715)
			(stroke
				(width 0.1524)
				(type default)
			)
			(layer "B.SilkS")
		)
		(fp_line
			(start -0.9525 2.4765)
			(end -1.778 2.4765)
			(stroke
				(width 0.1524)
				(type default)
			)
			(layer "B.SilkS")
		)
		(fp_line
			(start -0.381 0.635)
			(end -0.381 1.27)
			(stroke
				(width 0.1524)
				(type default)
			)
			(layer "B.SilkS")
		)
		(fp_circle
			(center 0.52197 -0.800608)
			(end 0.64897 -0.800608)
			(stroke
				(width 0.254)
				(type default)
			)
			(fill no)
			(layer "B.SilkS")
		)
		(fp_poly
			(pts
				(xy -1.778 2.4765) (xy -0.381 2.4765) (xy -0.381 -0.5715) (xy -1.778 -0.5715)
			)
			(stroke
				(width 0)
				(type default)
			)
			(fill no)
			(layer "B.CrtYd")
		)
		(fp_line
			(start -1.778 -0.5715)
			(end -0.381 -0.5715)
			(stroke
				(width 0.1)
				(type default)
			)
			(layer "B.Fab")
		)
		(fp_line
			(start -1.778 2.4765)
			(end -1.778 -0.5715)
			(stroke
				(width 0.1)
				(type default)
			)
			(layer "B.Fab")
		)
		(fp_line
			(start -0.381 -0.5715)
			(end -0.381 2.4765)
			(stroke
				(width 0.1)
				(type default)
			)
			(layer "B.Fab")
		)
		(fp_line
			(start -0.381 2.4765)
			(end -1.778 2.4765)
			(stroke
				(width 0.1)
				(type default)
			)
			(layer "B.Fab")
		)
		(fp_circle
			(center 0.9525 -0.9271)
			(end 1.0795 -0.9271)
			(stroke
				(width 0.254)
				(type default)
			)
			(fill no)
			(layer "B.Fab")
		)
		(pad "1" smd rect
			(at 0 0 180)
			(size 1.143 0.508)
			(layers "B.Cu" "B.Mask" "B.Paste")
			(net "FM_PMBUS_ALERT_BUF_EN_N")
		)
		(pad "2" smd rect
			(at 0 1.905 180)
			(size 1.143 0.508)
			(layers "B.Cu" "B.Mask" "B.Paste")
			(net "GND")
		)
		(pad "3" smd rect
			(at -2.159 0.9525 180)
			(size 1.143 0.508)
			(layers "B.Cu" "B.Mask" "B.Paste")
			(net "FM_PMBUS_ALERT_BUF_EN")
		)
	)
	(footprint ""
		(layer "B.Cu")
		(at 229.23881 -164.911786 90)
		(property "Reference" "T1D24"
			(at 0 0 90)
			(layer "B.SilkS")
			(hide yes)
			(effects
				(font
					(size 1.27 1.27)
				)
				(justify mirror)
			)
		)
		(property "Value" "*"
			(at 3.4036 -4.46405 90)
			(unlocked yes)
			(layer "B.Fab")
			(hide yes)
			(effects
				(font
					(size 0.889 0.889)
					(thickness 0.1524)
				)
				(justify mirror)
			)
		)
		(property "Device Type" "TEST-PAD-12P-1-GP-U_DISCRET-GBA"
			(at 3.4036 -5.98805 90)
			(unlocked yes)
			(layer "B.Fab")
			(hide yes)
			(effects
				(font
					(size 0.889 0.889)
					(thickness 0.1524)
				)
				(justify mirror)
			)
		)
		(duplicate_pad_numbers_are_jumpers no)
		(fp_line
			(start 2.3876 -4.826)
			(end -2.3622 -4.826)
			(stroke
				(width 0.1524)
				(type default)
			)
			(layer "B.SilkS")
		)
		(fp_line
			(start -2.3622 -4.826)
			(end -2.3622 3.4798)
			(stroke
				(width 0.1524)
				(type default)
			)
			(layer "B.SilkS")
		)
		(fp_line
			(start 2.3876 3.4798)
			(end 2.3876 -4.826)
			(stroke
				(width 0.1524)
				(type default)
			)
			(layer "B.SilkS")
		)
		(fp_line
			(start -2.3622 3.4798)
			(end 2.3876 3.4798)
			(stroke
				(width 0.1524)
				(type default)
			)
			(layer "B.SilkS")
		)
		(fp_rect
			(start 2.6416 3.7338)
			(end -2.6162 -5.08)
			(stroke
				(width 0)
				(type default)
			)
			(fill no)
			(layer "B.CrtYd")
		)
		(fp_rect
			(start 2.6416 3.7338)
			(end -2.6162 -5.08)
			(stroke
				(width 0)
				(type default)
			)
			(fill no)
			(layer "B.Fab")
		)
		(pad "1" smd circle
			(at -0.496824 -1.301496 270)
			(size 0.6604 0.6604)
			(layers "B.Cu" "B.Mask" "B.Paste")
			(net "L14_85OHM_10INCH_DN")
		)
		(pad "2" smd circle
			(at 0.503936 -1.301496 270)
			(size 0.6604 0.6604)
			(layers "B.Cu" "B.Mask" "B.Paste")
			(net "L14_85OHM_10INCH_DP")
		)
		(pad "3" smd custom
			(at 0.00889 0.370078 270)
			(size 0.74295 0.74295)
			(layers "B.Cu" "B.Mask" "B.Paste")
			(net "GND")
			(options
				(clearance outline)
				(anchor circle)
			)
			(primitives
				(gr_poly
					(pts
						(xy -2.1209 -1.4859) (xy 2.1209 -1.4859) (xy 2.1209 1.4859) (xy 1.08585 1.4859) (xy 1.08585 0.4699)
						(xy -1.08585 0.4699) (xy -1.08585 1.4859) (xy -2.1209 1.4859)
					)
					(width 0)
					(fill yes)
				)
			)
		)
		(pad "4" thru_hole circle
			(at -1.266444 -3.851656 270)
			(size 1.4478 1.4478)
			(drill 1.0414)
			(layers "*.Cu" "*.Mask")
			(remove_unused_layers no)
			(net "GND")
			(clearance 0.1524)
			(thermal_gap 0.1524)
		)
		(pad "5" thru_hole circle
			(at 1.273556 -3.851656 270)
			(size 1.4478 1.4478)
			(drill 1.0414)
			(layers "*.Cu" "*.Mask")
			(remove_unused_layers no)
			(net "GND")
			(clearance 0.1524)
			(thermal_gap 0.1524)
		)
		(pad "6" thru_hole circle
			(at -1.266444 2.498344 270)
			(size 1.4478 1.4478)
			(drill 1.0414)
			(layers "*.Cu" "*.Mask")
			(remove_unused_layers no)
			(net "GND")
			(clearance 0.1524)
			(thermal_gap 0.1524)
		)
		(pad "7" thru_hole circle
			(at 1.273556 2.498344 270)
			(size 1.4478 1.4478)
			(drill 1.0414)
			(layers "*.Cu" "*.Mask")
			(remove_unused_layers no)
			(net "GND")
			(clearance 0.1524)
			(thermal_gap 0.1524)
		)
		(pad "8" thru_hole circle
			(at -1.27 -0.4572 270)
			(size 0.7112 0.7112)
			(drill 0.4064)
			(layers "*.Cu" "*.Mask")
			(remove_unused_layers no)
			(net "GND")
			(clearance 0.1016)
			(thermal_gap 0.1016)
		)
		(pad "9" thru_hole circle
			(at -1.27 0.762 270)
			(size 0.7112 0.7112)
			(drill 0.4064)
			(layers "*.Cu" "*.Mask")
			(remove_unused_layers no)
			(net "GND")
			(clearance 0.1016)
			(thermal_gap 0.1016)
		)
		(pad "10" thru_hole circle
			(at 0.0254 0.762 270)
			(size 0.7112 0.7112)
			(drill 0.4064)
			(layers "*.Cu" "*.Mask")
			(remove_unused_layers no)
			(net "GND")
			(clearance 0.1016)
			(thermal_gap 0.1016)
		)
		(pad "11" thru_hole circle
			(at 1.27 0.762 270)
			(size 0.7112 0.7112)
			(drill 0.4064)
			(layers "*.Cu" "*.Mask")
			(remove_unused_layers no)
			(net "GND")
			(clearance 0.1016)
			(thermal_gap 0.1016)
		)
		(pad "12" thru_hole circle
			(at 1.27 -0.4572 270)
			(size 0.7112 0.7112)
			(drill 0.4064)
			(layers "*.Cu" "*.Mask")
			(remove_unused_layers no)
			(net "GND")
			(clearance 0.1016)
			(thermal_gap 0.1016)
		)
	)
)
